# BASEBOARD_FAB2 (Tioga Pass) — schematic netlist excerpt (pin names and nets, part order shuffled) for the footprints in the layout excerpt that follows; sources: Cadence DE-HDL packaged netlist, KiCad conversion of Wiwynn_Tioga_Pass_MB.brd

C5G99  CAP_A  22.0UF 4V 20% X6S  pkg 0603V  page 243 : A = PVDDQ_KLM ; B = GND
C3M32  CAP  0.22UF 16V 10% X7R  pkg 0402  page 105 : A = P3E_CPU0_PE1_PCH_R_RXN<10> ; B = P3E_CPU0_PE1_PCH_RXN<10>
C7E3  CAP_A  0.1UF 16V 10% X7R  pkg 0402V  page 95 : A = P3V3_STBY ; B = GND

(kicad_pcb
	(version 20260206)
	(generator "pcbnew")
	(generator_version "10.0")
	(general
		(thickness 1.6)
		(legacy_teardrops no)
	)
	(paper "A4")
	(title_block
		(title "Wiwynn_Tioga_Pass_MB.brd")
		(comment 1 "Tioga Pass / footprints 3765-3767 of 4770")
	)
	(layers
		(0 "F.Cu" signal "TOP")
		(4 "In1.Cu" signal "L2GND")
		(6 "In2.Cu" signal "L3")
		(8 "In3.Cu" signal "L4GND")
		(10 "In4.Cu" signal "L5")
		(12 "In5.Cu" signal "L6GND")
		(14 "In6.Cu" signal "L7VCC")
		(16 "In7.Cu" signal "L8VCC")
		(18 "In8.Cu" signal "L9GND")
		(20 "In9.Cu" signal "L10")
		(22 "In10.Cu" signal "L11GND")
		(24 "In11.Cu" signal "L12")
		(26 "In12.Cu" signal "L13GND")
		(2 "B.Cu" signal "BOTTOM")
		(9 "F.Adhes" user "F.Adhesive")
		(11 "B.Adhes" user "B.Adhesive")
		(13 "F.Paste" user "Package Geometry/Pastemask Top")
		(15 "B.Paste" user "Package Geometry/Pastemask Bottom")
		(5 "F.SilkS" user "Ref Des/Silkscreen Top")
		(7 "B.SilkS" user "Ref Des/Silkscreen Bottom")
		(1 "F.Mask" user "Board Geometry/Soldermask Top")
		(3 "B.Mask" user "Board Geometry/Soldermask Bottom")
		(17 "Dwgs.User" user "User.Drawings")
		(19 "Cmts.User" user "User.Comments")
		(21 "Eco1.User" user "User.Eco1")
		(23 "Eco2.User" user "User.Eco2")
		(25 "Edge.Cuts" user "Board Geometry/Outline")
		(27 "Margin" user)
		(31 "F.CrtYd" user "Package Geometry/Place Bound Top")
		(29 "B.CrtYd" user "Package Geometry/Place Bound Bottom")
		(35 "F.Fab" user "Ref Des/Assembly Top")
		(33 "B.Fab" user "Ref Des/Assembly Bottom")
	)
	(footprint ""
		(layer "B.Cu")
		(at 87.158068 -149.8092 -90)
		(property "Reference" "C5G99"
			(at -1.14681 0.76708 0)
			(unlocked yes)
			(layer "B.SilkS")
			(effects
				(font
					(size 0.7874 0.5842)
					(thickness 0.1524)
				)
				(justify mirror)
			)
		)
		(property "Value" ""
			(at 0 0 90)
			(layer "B.Fab")
			(effects
				(font
					(size 1.27 1.27)
				)
				(justify mirror)
			)
		)
		(duplicate_pad_numbers_are_jumpers no)
		(fp_rect
			(start 0.4953 1.6002)
			(end -0.4953 -0.2032)
			(stroke
				(width 0)
				(type default)
			)
			(fill no)
			(layer "B.CrtYd")
		)
		(fp_line
			(start -0.4953 1.6002)
			(end 0.4953 1.6002)
			(stroke
				(width 0.1)
				(type default)
			)
			(layer "B.Fab")
		)
		(fp_line
			(start 0.4953 1.6002)
			(end 0.4953 -0.2032)
			(stroke
				(width 0.1)
				(type default)
			)
			(layer "B.Fab")
		)
		(fp_line
			(start -0.4953 -0.2032)
			(end -0.4953 1.6002)
			(stroke
				(width 0.1)
				(type default)
			)
			(layer "B.Fab")
		)
		(fp_line
			(start 0.4953 -0.2032)
			(end -0.4953 -0.2032)
			(stroke
				(width 0.1)
				(type default)
			)
			(layer "B.Fab")
		)
		(pad "1" smd rect
			(at 0 0 90)
			(size 0.762 0.889)
			(layers "B.Cu" "B.Mask" "B.Paste")
			(net "PVDDQ_KLM")
		)
		(pad "2" smd rect
			(at 0 1.397 90)
			(size 0.762 0.889)
			(layers "B.Cu" "B.Mask" "B.Paste")
			(net "GND")
		)
		(zone
			(layer "B.Cu")
			(hatch none 0.5)
			(connect_pads
				(clearance 0)
			)
			(min_thickness 0.25)
			(keepout
				(tracks not_allowed)
				(vias allowed)
				(pads allowed)
				(copperpour not_allowed)
				(footprints allowed)
			)
			(placement
				(enabled no)
				(sheetname "")
			)
			(fill
				(thermal_gap 0.5)
				(thermal_bridge_width 0.5)
				(island_removal_mode 0)
			)
			(polygon
				(pts
					(xy 86.205568 -149.4282) (xy 86.713568 -149.4282) (xy 86.713568 -150.1902) (xy 86.205568 -150.1902)
				)
			)
		)
	)
	(footprint ""
		(layer "B.Cu")
		(at 362.671614 -124.440442 -90)
		(property "Reference" "C3M32"
			(at 0 0 90)
			(layer "B.SilkS")
			(hide yes)
			(effects
				(font
					(size 1.27 1.27)
				)
				(justify mirror)
			)
		)
		(property "Value" ""
			(at 0 0 90)
			(layer "B.Fab")
			(effects
				(font
					(size 1.27 1.27)
				)
				(justify mirror)
			)
		)
		(duplicate_pad_numbers_are_jumpers no)
		(fp_poly
			(pts
				(xy -0.3048 -0.1016) (xy -0.3048 0.9906) (xy 0.3048 0.9906) (xy 0.3048 -0.1016)
			)
			(stroke
				(width 0)
				(type default)
			)
			(fill no)
			(layer "B.CrtYd")
		)
		(fp_line
			(start -0.3048 0.9906)
			(end -0.3048 -0.1016)
			(stroke
				(width 0.1)
				(type default)
			)
			(layer "B.Fab")
		)
		(fp_line
			(start 0.3048 0.9906)
			(end -0.3048 0.9906)
			(stroke
				(width 0.1)
				(type default)
			)
			(layer "B.Fab")
		)
		(fp_line
			(start -0.3048 -0.1016)
			(end 0.3048 -0.1016)
			(stroke
				(width 0.1)
				(type default)
			)
			(layer "B.Fab")
		)
		(fp_line
			(start 0.3048 -0.1016)
			(end 0.3048 0.9906)
			(stroke
				(width 0.1)
				(type default)
			)
			(layer "B.Fab")
		)
		(pad "1" smd rect
			(at 0 0 90)
			(size 0.508 0.508)
			(layers "B.Cu" "B.Mask" "B.Paste")
			(net "P3E_CPU0_PE1_PCH_R_RXN<10>")
		)
		(pad "2" smd rect
			(at 0 0.889 90)
			(size 0.508 0.508)
			(layers "B.Cu" "B.Mask" "B.Paste")
			(net "P3E_CPU0_PE1_PCH_RXN<10>")
		)
		(zone
			(layer "B.Cu")
			(hatch none 0.5)
			(connect_pads
				(clearance 0)
			)
			(min_thickness 0.25)
			(keepout
				(tracks not_allowed)
				(vias allowed)
				(pads allowed)
				(copperpour not_allowed)
				(footprints allowed)
			)
			(placement
				(enabled no)
				(sheetname "")
			)
			(fill
				(thermal_gap 0.5)
				(thermal_bridge_width 0.5)
				(island_removal_mode 0)
			)
			(polygon
				(pts
					(xy 362.036614 -124.186442) (xy 362.036614 -124.694442) (xy 362.417614 -124.694442) (xy 362.417614 -124.186442)
				)
			)
		)
		(zone
			(layer "B.Cu")
			(hatch none 0.5)
			(connect_pads
				(clearance 0)
			)
			(min_thickness 0.25)
			(keepout
				(tracks allowed)
				(vias not_allowed)
				(pads allowed)
				(copperpour not_allowed)
				(footprints allowed)
			)
			(placement
				(enabled no)
				(sheetname "")
			)
			(fill
				(thermal_gap 0.5)
				(thermal_bridge_width 0.5)
				(island_removal_mode 0)
			)
			(polygon
				(pts
					(xy 362.417614 -124.186442) (xy 362.417614 -124.694442) (xy 362.036614 -124.694442) (xy 362.036614 -124.186442)
				)
			)
		)
	)
	(footprint ""
		(layer "B.Cu")
		(at 373.017288 -36.096448 90)
		(property "Reference" "C7E3"
			(at 0 0 90)
			(layer "B.SilkS")
			(hide yes)
			(effects
				(font
					(size 1.27 1.27)
				)
				(justify mirror)
			)
		)
		(property "Value" ""
			(at 0 0 90)
			(layer "B.Fab")
			(effects
				(font
					(size 1.27 1.27)
				)
				(justify mirror)
			)
		)
		(duplicate_pad_numbers_are_jumpers no)
		(fp_poly
			(pts
				(xy -0.3048 -0.1016) (xy -0.3048 0.9906) (xy 0.3048 0.9906) (xy 0.3048 -0.1016)
			)
			(stroke
				(width 0)
				(type default)
			)
			(fill no)
			(layer "B.CrtYd")
		)
		(fp_line
			(start 0.3048 -0.1016)
			(end 0.3048 0.9906)
			(stroke
				(width 0.1)
				(type default)
			)
			(layer "B.Fab")
		)
		(fp_line
			(start -0.3048 -0.1016)
			(end 0.3048 -0.1016)
			(stroke
				(width 0.1)
				(type default)
			)
			(layer "B.Fab")
		)
		(fp_line
			(start 0.3048 0.9906)
			(end -0.3048 0.9906)
			(stroke
				(width 0.1)
				(type default)
			)
			(layer "B.Fab")
		)
		(fp_line
			(start -0.3048 0.9906)
			(end -0.3048 -0.1016)
			(stroke
				(width 0.1)
				(type default)
			)
			(layer "B.Fab")
		)
		(pad "1" smd rect
			(at 0 0 270)
			(size 0.508 0.508)
			(layers "B.Cu" "B.Mask" "B.Paste")
			(net "P3V3_STBY")
		)
		(pad "2" smd rect
			(at 0 0.889 270)
			(size 0.508 0.508)
			(layers "B.Cu" "B.Mask" "B.Paste")
			(net "GND")
		)
		(zone
			(layer "B.Cu")
			(hatch none 0.5)
			(connect_pads
				(clearance 0)
			)
			(min_thickness 0.25)
			(keepout
				(tracks allowed)
				(vias not_allowed)
				(pads allowed)
				(copperpour not_allowed)
				(footprints allowed)
			)
			(placement
				(enabled no)
				(sheetname "")
			)
			(fill
				(thermal_gap 0.5)
				(thermal_bridge_width 0.5)
				(island_removal_mode 0)
			)
			(polygon
				(pts
					(xy 373.271288 -36.350448) (xy 373.271288 -35.842448) (xy 373.652288 -35.842448) (xy 373.652288 -36.350448)
				)
			)
		)
		(zone
			(layer "B.Cu")
			(hatch none 0.5)
			(connect_pads
				(clearance 0)
			)
			(min_thickness 0.25)
			(keepout
				(tracks not_allowed)
				(vias allowed)
				(pads allowed)
				(copperpour not_allowed)
				(footprints allowed)
			)
			(placement
				(enabled no)
				(sheetname "")
			)
			(fill
				(thermal_gap 0.5)
				(thermal_bridge_width 0.5)
				(island_removal_mode 0)
			)
			(polygon
				(pts
					(xy 373.652288 -36.350448) (xy 373.652288 -35.842448) (xy 373.271288 -35.842448) (xy 373.271288 -36.350448)
				)
			)
		)
	)
)
